# S9S_MB_2U (Grand Teton) — schematic netlist excerpt (pin names and nets, part order shuffled) for the footprints in the layout excerpt that follows; sources: Cadence DE-HDL packaged netlist, KiCad conversion of 03242023_DA0F0TMBIJ0_F0T_Motherboard_J_brd_V01_OCP.brd

R3050  Q_RES  33.2 1% CHIP  pkg 0402LF  page 223 : A = RST_RSMRST_PLD_R_N ; B = RST_RSMRST_NM_HDR_N
R1150  Q_RES  10K 1% CHIP  pkg 0402LF  page 156 : A = P3V3_AUX ; B = HP_LVC3_OCP_V3_1_PRSNT2_N

(kicad_pcb
	(version 20260206)
	(generator "pcbnew")
	(generator_version "10.0")
	(general
		(thickness 1.6)
		(legacy_teardrops no)
	)
	(paper "A4")
	(title_block
		(title "03242023_DA0F0TMBIJ0_F0T_Motherboard_J_brd_V01_OCP.brd")
		(comment 1 "Grand Teton / footprints 1724-1725 of 6105")
	)
	(layers
		(0 "F.Cu" signal "TOP")
		(4 "In1.Cu" signal "GND")
		(6 "In2.Cu" signal "IN1")
		(8 "In3.Cu" signal "GND1")
		(10 "In4.Cu" signal "IN2")
		(12 "In5.Cu" signal "GND2")
		(14 "In6.Cu" signal "IN3")
		(16 "In7.Cu" signal "GND3")
		(18 "In8.Cu" signal "VCC")
		(20 "In9.Cu" signal "VCC1")
		(22 "In10.Cu" signal "GND4")
		(24 "In11.Cu" signal "IN4")
		(26 "In12.Cu" signal "GND5")
		(28 "In13.Cu" signal "IN5")
		(30 "In14.Cu" signal "GND6")
		(32 "In15.Cu" signal "IN6")
		(34 "In16.Cu" signal "GND7")
		(2 "B.Cu" signal "BOTTOM")
		(9 "F.Adhes" user "F.Adhesive")
		(11 "B.Adhes" user "B.Adhesive")
		(13 "F.Paste" user "Package Geometry/Pastemask Top")
		(15 "B.Paste" user "Package Geometry/Pastemask Bottom")
		(5 "F.SilkS" user "Ref Des/Silkscreen Top")
		(7 "B.SilkS" user "Ref Des/Silkscreen Bottom")
		(1 "F.Mask" user "Board Geometry/Soldermask Top")
		(3 "B.Mask" user "Board Geometry/Soldermask Bottom")
		(17 "Dwgs.User" user "User.Drawings")
		(19 "Cmts.User" user "User.Comments")
		(21 "Eco1.User" user "User.Eco1")
		(23 "Eco2.User" user "User.Eco2")
		(25 "Edge.Cuts" user "Board Geometry/Outline")
		(27 "Margin" user)
		(31 "F.CrtYd" user "Package Geometry/Place Bound Top")
		(29 "B.CrtYd" user "Package Geometry/Place Bound Bottom")
		(35 "F.Fab" user "Ref Des/Assembly Top")
		(33 "B.Fab" user "Ref Des/Assembly Bottom")
	)
	(footprint ""
		(layer "F.Cu")
		(at 9.58088 -52.923948)
		(property "Reference" "R3050"
			(at 0 0 0)
			(layer "F.SilkS")
			(hide yes)
			(effects
				(font
					(size 1.27 1.27)
				)
			)
		)
		(property "Value" ""
			(at 0 0 0)
			(layer "F.Fab")
			(effects
				(font
					(size 1.27 1.27)
				)
			)
		)
		(duplicate_pad_numbers_are_jumpers no)
		(fp_line
			(start -0.7874 -0.4064)
			(end 0.7874 -0.4064)
			(stroke
				(width 0.1524)
				(type default)
			)
			(layer "F.SilkS")
		)
		(fp_line
			(start -0.7874 0.4064)
			(end -0.7874 -0.4064)
			(stroke
				(width 0.1524)
				(type default)
			)
			(layer "F.SilkS")
		)
		(fp_line
			(start 0.7874 -0.4064)
			(end 0.7874 0.4064)
			(stroke
				(width 0.1524)
				(type default)
			)
			(layer "F.SilkS")
		)
		(fp_line
			(start 0.7874 0.4064)
			(end -0.7874 0.4064)
			(stroke
				(width 0.1524)
				(type default)
			)
			(layer "F.SilkS")
		)
		(fp_line
			(start -0.67945 -0.305054)
			(end -0.12065 -0.305054)
			(stroke
				(width 0.1)
				(type default)
			)
			(layer "F.Fab")
		)
		(fp_line
			(start -0.67945 0.3048)
			(end -0.67945 -0.305054)
			(stroke
				(width 0.1)
				(type default)
			)
			(layer "F.Fab")
		)
		(fp_line
			(start -0.12065 -0.305054)
			(end -0.12065 -0.2794)
			(stroke
				(width 0.1)
				(type default)
			)
			(layer "F.Fab")
		)
		(fp_line
			(start -0.12065 -0.2794)
			(end 0.12065 -0.2794)
			(stroke
				(width 0.1)
				(type default)
			)
			(layer "F.Fab")
		)
		(fp_line
			(start -0.12065 0.2794)
			(end -0.12065 0.3048)
			(stroke
				(width 0.1)
				(type default)
			)
			(layer "F.Fab")
		)
		(fp_line
			(start -0.12065 0.3048)
			(end -0.67945 0.3048)
			(stroke
				(width 0.1)
				(type default)
			)
			(layer "F.Fab")
		)
		(fp_line
			(start 0.120396 0.2794)
			(end -0.12065 0.2794)
			(stroke
				(width 0.1)
				(type default)
			)
			(layer "F.Fab")
		)
		(fp_line
			(start 0.120396 0.3048)
			(end 0.120396 0.2794)
			(stroke
				(width 0.1)
				(type default)
			)
			(layer "F.Fab")
		)
		(fp_line
			(start 0.12065 -0.3048)
			(end 0.67945 -0.3048)
			(stroke
				(width 0.1)
				(type default)
			)
			(layer "F.Fab")
		)
		(fp_line
			(start 0.12065 -0.2794)
			(end 0.12065 -0.3048)
			(stroke
				(width 0.1)
				(type default)
			)
			(layer "F.Fab")
		)
		(fp_line
			(start 0.67945 -0.3048)
			(end 0.67945 0.3048)
			(stroke
				(width 0.1)
				(type default)
			)
			(layer "F.Fab")
		)
		(fp_line
			(start 0.67945 0.3048)
			(end 0.120396 0.3048)
			(stroke
				(width 0.1)
				(type default)
			)
			(layer "F.Fab")
		)
		(pad "1" smd circle
			(at -0.40005 0)
			(size 0 0)
			(layers "F.Cu" "F.Mask" "F.Paste")
			(net "RST_RSMRST_PLD_R_N")
		)
		(pad "2" smd circle
			(at 0.40005 0)
			(size 0 0)
			(layers "F.Cu" "F.Mask" "F.Paste")
			(net "RST_RSMRST_NM_HDR_N")
		)
	)
	(footprint ""
		(layer "F.Cu")
		(at 463.636106 -110.287308 180)
		(property "Reference" "R1150"
			(at 0 0 180)
			(layer "F.SilkS")
			(hide yes)
			(effects
				(font
					(size 1.27 1.27)
				)
			)
		)
		(property "Value" ""
			(at 0 0 180)
			(layer "F.Fab")
			(effects
				(font
					(size 1.27 1.27)
				)
			)
		)
		(duplicate_pad_numbers_are_jumpers no)
		(fp_line
			(start 0.7874 0.4064)
			(end -0.7874 0.4064)
			(stroke
				(width 0.1524)
				(type default)
			)
			(layer "F.SilkS")
		)
		(fp_line
			(start 0.7874 -0.4064)
			(end 0.7874 0.4064)
			(stroke
				(width 0.1524)
				(type default)
			)
			(layer "F.SilkS")
		)
		(fp_line
			(start -0.7874 0.4064)
			(end -0.7874 -0.4064)
			(stroke
				(width 0.1524)
				(type default)
			)
			(layer "F.SilkS")
		)
		(fp_line
			(start -0.7874 -0.4064)
			(end 0.7874 -0.4064)
			(stroke
				(width 0.1524)
				(type default)
			)
			(layer "F.SilkS")
		)
		(fp_line
			(start 0.67945 0.3048)
			(end 0.120396 0.3048)
			(stroke
				(width 0.1)
				(type default)
			)
			(layer "F.Fab")
		)
		(fp_line
			(start 0.67945 -0.3048)
			(end 0.67945 0.3048)
			(stroke
				(width 0.1)
				(type default)
			)
			(layer "F.Fab")
		)
		(fp_line
			(start 0.12065 -0.2794)
			(end 0.12065 -0.3048)
			(stroke
				(width 0.1)
				(type default)
			)
			(layer "F.Fab")
		)
		(fp_line
			(start 0.12065 -0.3048)
			(end 0.67945 -0.3048)
			(stroke
				(width 0.1)
				(type default)
			)
			(layer "F.Fab")
		)
		(fp_line
			(start 0.120396 0.3048)
			(end 0.120396 0.2794)
			(stroke
				(width 0.1)
				(type default)
			)
			(layer "F.Fab")
		)
		(fp_line
			(start 0.120396 0.2794)
			(end -0.12065 0.2794)
			(stroke
				(width 0.1)
				(type default)
			)
			(layer "F.Fab")
		)
		(fp_line
			(start -0.12065 0.3048)
			(end -0.67945 0.3048)
			(stroke
				(width 0.1)
				(type default)
			)
			(layer "F.Fab")
		)
		(fp_line
			(start -0.12065 0.2794)
			(end -0.12065 0.3048)
			(stroke
				(width 0.1)
				(type default)
			)
			(layer "F.Fab")
		)
		(fp_line
			(start -0.12065 -0.2794)
			(end 0.12065 -0.2794)
			(stroke
				(width 0.1)
				(type default)
			)
			(layer "F.Fab")
		)
		(fp_line
			(start -0.12065 -0.305054)
			(end -0.12065 -0.2794)
			(stroke
				(width 0.1)
				(type default)
			)
			(layer "F.Fab")
		)
		(fp_line
			(start -0.67945 0.3048)
			(end -0.67945 -0.305054)
			(stroke
				(width 0.1)
				(type default)
			)
			(layer "F.Fab")
		)
		(fp_line
			(start -0.67945 -0.305054)
			(end -0.12065 -0.305054)
			(stroke
				(width 0.1)
				(type default)
			)
			(layer "F.Fab")
		)
		(pad "1" smd circle
			(at -0.40005 0 180)
			(size 0 0)
			(layers "F.Cu" "F.Mask" "F.Paste")
			(net "P3V3_AUX")
		)
		(pad "2" smd circle
			(at 0.40005 0 180)
			(size 0 0)
			(layers "F.Cu" "F.Mask" "F.Paste")
			(net "HP_LVC3_OCP_V3_1_PRSNT2_N")
		)
	)
)
